FILE_TYPE = MULTI_PHYS_TABLE;

PART '74LVC1G02GW'

{========================================================================================}
:VALUE         | PACK_TYPE | MATERIAL | PART_NUMBER           = STANDARD         | LIFECYCLE        | ENVCOMP | PART_NUMBER        | JEDEC_TYPE   | CLASS | DESCRIPTION                  | HEIGHT   | COMPONENT_TYPE | LEAD_LENGTH | LPID| DAY ;
{========================================================================================}
 '74LVC1G02GW' | 'SMLF'    | 'IC'     | 'ALVC1G02000'(!) = ''               | ''               | 'YES'   | 'ALVC1G02000' |'SOT353_Q'| 'IC'  | 'IC(5P) 74LVC1G02GW(SOT353)' | '.044IN' | 'SMALLSMT'     | ''          | ''  | '20100711'
 '74LVC1G02GW' | 'SMLF'    | 'EMPTY'  | 'ALVC1G02000'(!) = ''               | ''               | 'YES'   | 'ALVC1G02000' |'SOT353_Q'| 'IO'  | 'IC(5P) 74LVC1G02GW(SOT353)' | '.044IN' | 'SMALLSMT'     | ''          | ''  | '20100711'

END_PART

END.

